FILE_TYPE = CONNECTIVITY;
{Allegro Design Entry HDL 17.2-2016 S081 (4005846) 1/11/2022}
"PAGE_NUMBER" = 305;
0"NC";
1"P3V3_AUX\g";
2"P3V3_AUX\g";
3"P3V3_AUX\g";
4"P3V3_AUX\g";
5"P3V3_AUX\g";
6"P3V3_AUX\g";
7"P3V3_AUX\g";
8"GND\g";
9"GND\g";
10"GND\g";
11"GND\g";
12"GND\g";
13"GND\g";
14"GND\g";
15"LED_PWRGD_PVCCINFAON_CPU0_D";
16"LED_PWRGD_PVPP_HBM_CPU0";
17"PWRGD_PVCCINFAON_CPU0";
18"LED_PWRGD_PVNN_MAIN_CPU0_D";
19"LED_PWRGD_PVCCFA_EHV_FIVRA_CPU0";
20"LED_PWRGD_PVCCFA_EHV_FIVRA_CPU0_D";
21"LED_PWRGD_PVCCFA_EHV_CPU0_D";
22"LED_PWRGD_PVPP_HBM_CPU0_D";
23"LED_PWRGD_PVCCD_HV_CPU0";
24"LED_PWRGD_PVCCFA_EHV_CPU0";
25"PWRGD_PVCCIN_CPU0";
26"PWRGD_PVNN_MAIN_CPU0";
27"LED_PWRGD_PVCCIN_CPU0";
28"LED_PWRGD_PVNN_MAIN_CPU0";
29"LED_PWRGD_PVCCINFAON_CPU0";
30"LED_PWRGD_PVCCIN_CPU0_D";
31"LED_PWRGD_PVCCD_HV_CPU0_D";
32"PWRGD_PVCCD_HV_CPU0";
33"PWRGD_PVPP_HBM_CPU0";
34"PWRGD_PVCCFA_EHV_CPU0";
35"PWRGD_PVCCFA_EHV_FIVRA_CPU0";
%"Q_LED"
"1","(-1575,825)","2","pure_quanta","I10";
;
PART_NUMBER"BEBL0172Z00"
MATERIAL"IC"
MANUF_PN"LTST-C281TBKT-5A"
PACK_TYPE"SMLF"
COLOR"LED_BLUE"
LOCATION"D76"
CDS_LIB"pure_quanta"
NEEDS_NO_SIZE"TRUE"
$SEC"1"
CDS_SEC"1";
"A"
$PN"A"19;
"C"
$PN"C"20;
%"UNIVERSAL_GND"
"1","(-2600,1525)","0","logical_power","I11";
;
CDS_LIB"logical_power"
HDL_POWER"GND";
"A"9;
%"UNIVERSAL_GND"
"1","(-2600,2750)","0","logical_power","I12";
;
CDS_LIB"logical_power"
HDL_POWER"GND";
"A"10;
%"Q_LED"
"1","(-1575,2150)","2","pure_quanta","I13";
;
PART_NUMBER"BEBL0172Z00"
PACK_TYPE"SMLF"
MATERIAL"IC"
COLOR"LED_BLUE"
MANUF_PN"LTST-C281TBKT-5A"
LOCATION"D75"
CDS_LIB"pure_quanta"
NEEDS_NO_SIZE"TRUE"
$SEC"1"
CDS_SEC"1";
"A"
$PN"A"24;
"C"
$PN"C"21;
%"UNIVERSAL_POWER"
"1","(400,975)","0","logical_power","I17";
;
HDL_POWER"P3V3_AUX"
CDS_LIB"logical_power";
"A"3;
%"UNIVERSAL_POWER"
"1","(450,2325)","0","logical_power","I19";
;
HDL_POWER"P3V3_AUX"
CDS_LIB"logical_power";
"A"2;
%"MOSFET_NCH_DUAL"
"2","(-2650,550)","0","pure_quanta","I2";
;
PART_NUMBER"BAM138K0003"
VALUE"PJT138K"
MATERIAL"IC"
PART_TYPE"SMLF"
LOCATION"Q80"
CDS_LMAN_SYM_OUTLINE"-150,150,150,-150"
NEEDS_NO_SIZE"TRUE"
CDS_LIB"pure_quanta"
SEC_TYPE""
SEC"2";
"S2"
$PN"4"8;
"G2"
$PN"5"35;
"D2"
$PN"3"20;
%"UNIVERSAL_GND"
"1","(-2600,4075)","0","logical_power","I20";
;
CDS_LIB"logical_power"
HDL_POWER"GND";
"A"11;
%"Q_LED"
"1","(-1575,3375)","2","pure_quanta","I21";
;
PART_NUMBER"BEBL0172Z00"
PACK_TYPE"SMLF"
MANUF_PN"LTST-C281TBKT-5A"
MATERIAL"IC"
COLOR"LED_BLUE"
LOCATION"D74"
CDS_LIB"pure_quanta"
NEEDS_NO_SIZE"TRUE"
$SEC"1"
CDS_SEC"1";
"A"
$PN"A"16;
"C"
$PN"C"22;
%"Q_LED"
"1","(-1575,4700)","2","pure_quanta","I22";
;
PART_NUMBER"BEBL0172Z00"
MATERIAL"IC"
MANUF_PN"LTST-C281TBKT-5A"
COLOR"LED_BLUE"
PACK_TYPE"SMLF"
LOCATION"D73"
NEEDS_NO_SIZE"TRUE"
CDS_LIB"pure_quanta"
$SEC"1"
CDS_SEC"1";
"A"
$PN"A"23;
"C"
$PN"C"31;
%"UNIVERSAL_POWER"
"1","(400,3500)","0","logical_power","I25";
;
HDL_POWER"P3V3_AUX"
CDS_LIB"logical_power";
"A"1;
%"UNIVERSAL_POWER"
"1","(425,4850)","0","logical_power","I27";
;
HDL_POWER"P3V3_AUX"
CDS_LIB"logical_power";
"A"4;
%"MOSFET_NCH_DUAL"
"1","(2125,1850)","0","pure_quanta","I32";
;
PART_NUMBER"BAM138K0003"
MATERIAL"IC"
PART_TYPE"SMLF"
VALUE"PJT138K"
LOCATION"Q83"
NEEDS_NO_SIZE"TRUE"
CDS_LMAN_SYM_OUTLINE"-150,150,150,-150"
CDS_LIB"pure_quanta"
$SEC"1"
CDS_SEC"1";
"D1"
$PN"6"30;
"G1"
$PN"2"25;
"S1"
$PN"1"12;
%"UNIVERSAL_GND"
"1","(2175,1500)","0","logical_power","I33";
;
CDS_LIB"logical_power"
HDL_POWER"GND";
"A"12;
%"UNIVERSAL_GND"
"1","(2175,2750)","0","logical_power","I34";
;
CDS_LIB"logical_power"
HDL_POWER"GND";
"A"13;
%"Q_LED"
"1","(3200,2125)","2","pure_quanta","I35";
;
PART_NUMBER"BEBL0172Z00"
MANUF_PN"LTST-C281TBKT-5A"
PACK_TYPE"SMLF"
COLOR"LED_BLUE"
MATERIAL"IC"
LOCATION"D79"
NEEDS_NO_SIZE"TRUE"
CDS_LIB"pure_quanta"
$SEC"1"
CDS_SEC"1";
"A"
$PN"A"27;
"C"
$PN"C"30;
%"UNIVERSAL_POWER"
"1","(5175,2275)","0","logical_power","I39";
;
HDL_POWER"P3V3_AUX"
CDS_LIB"logical_power";
"A"5;
%"MOSFET_NCH_DUAL"
"1","(-2650,1875)","0","pure_quanta","I4";
;
PART_NUMBER"BAM138K0003"
MATERIAL"IC"
PART_TYPE"SMLF"
VALUE"PJT138K"
LOCATION"Q80"
CDS_LIB"pure_quanta"
CDS_LMAN_SYM_OUTLINE"-150,150,150,-150"
NEEDS_NO_SIZE"TRUE"
$SEC"1"
CDS_SEC"1";
"D1"
$PN"6"21;
"G1"
$PN"2"34;
"S1"
$PN"1"9;
%"MOSFET_NCH_DUAL"
"2","(2125,3100)","0","pure_quanta","I40";
;
PART_NUMBER"BAM138K0003"
MATERIAL"IC"
VALUE"PJT138K"
PART_TYPE"SMLF"
LOCATION"Q81"
CDS_LMAN_SYM_OUTLINE"-150,150,150,-150"
NEEDS_NO_SIZE"TRUE"
CDS_LIB"pure_quanta"
SEC_TYPE""
SEC"2";
"S2"
$PN"4"13;
"G2"
$PN"5"26;
"D2"
$PN"3"18;
%"MOSFET_NCH_DUAL"
"1","(2125,4425)","0","pure_quanta","I41";
;
PART_NUMBER"BAM138K0003"
PART_TYPE"SMLF"
VALUE"PJT138K"
MATERIAL"IC"
LOCATION"Q81"
CDS_LIB"pure_quanta"
CDS_LMAN_SYM_OUTLINE"-150,150,150,-150"
NEEDS_NO_SIZE"TRUE"
$SEC"1"
CDS_SEC"1";
"D1"
$PN"6"15;
"G1"
$PN"2"17;
"S1"
$PN"1"14;
%"UNIVERSAL_GND"
"1","(2175,4075)","0","logical_power","I42";
;
CDS_LIB"logical_power"
HDL_POWER"GND";
"A"14;
%"Q_LED"
"1","(3200,3375)","2","pure_quanta","I43";
;
PART_NUMBER"BEBL0172Z00"
MATERIAL"IC"
MANUF_PN"LTST-C281TBKT-5A"
PACK_TYPE"SMLF"
COLOR"LED_BLUE"
LOCATION"D78"
NEEDS_NO_SIZE"TRUE"
CDS_LIB"pure_quanta"
$SEC"1"
CDS_SEC"1";
"A"
$PN"A"28;
"C"
$PN"C"18;
%"Q_LED"
"1","(3200,4700)","2","pure_quanta","I44";
;
PART_NUMBER"BEBL0172Z00"
MATERIAL"IC"
MANUF_PN"LTST-C281TBKT-5A"
COLOR"LED_BLUE"
PACK_TYPE"SMLF"
LOCATION"D77"
CDS_LIB"pure_quanta"
NEEDS_NO_SIZE"TRUE"
$SEC"1"
CDS_SEC"1";
"A"
$PN"A"29;
"C"
$PN"C"15;
%"UNIVERSAL_POWER"
"1","(5150,3525)","0","logical_power","I46";
;
HDL_POWER"P3V3_AUX"
CDS_LIB"logical_power";
"A"6;
%"UNIVERSAL_POWER"
"1","(5125,4875)","0","logical_power","I48";
;
HDL_POWER"P3V3_AUX"
CDS_LIB"logical_power";
"A"7;
%"Q_RES"
"1","(-225,4700)","0","pure_quanta","I49";
;
PART_NUMBER"CS11302FB03"
PACK_TYPE"0402LF"
VALUE"130"
TOLERANCE"1%"
WATTAGE"1/16W"
MATERIAL"CHIP"
$LOCATION"R3086"
CDS_LIB"pure_quanta"
CDS_LOCATION"R3086"
$SEC"1"
CDS_SEC"1";
"B"
$PN"2"4;
"A"
$PN"1"23;
%"Q_RES"
"1","(-200,3375)","0","pure_quanta","I50";
;
PART_NUMBER"CS11302FB03"
WATTAGE"1/16W"
MATERIAL"CHIP"
PACK_TYPE"0402LF"
TOLERANCE"1%"
VALUE"130"
$LOCATION"R3087"
CDS_LIB"pure_quanta"
CDS_LOCATION"R3087"
$SEC"1"
CDS_SEC"1";
"B"
$PN"2"1;
"A"
$PN"1"16;
%"Q_RES"
"1","(-150,2150)","0","pure_quanta","I51";
;
PART_NUMBER"CS11302FB03"
PACK_TYPE"0402LF"
VALUE"130"
TOLERANCE"1%"
WATTAGE"1/16W"
MATERIAL"CHIP"
$LOCATION"R3089"
CDS_LIB"pure_quanta"
CDS_LOCATION"R3089"
$SEC"1"
CDS_SEC"1";
"B"
$PN"2"2;
"A"
$PN"1"24;
%"Q_RES"
"1","(-200,825)","0","pure_quanta","I52";
;
PART_NUMBER"CS11302FB03"
PACK_TYPE"0402LF"
WATTAGE"1/16W"
MATERIAL"CHIP"
TOLERANCE"1%"
VALUE"130"
$LOCATION"R3088"
CDS_LIB"pure_quanta"
CDS_LOCATION"R3088"
$SEC"1"
CDS_SEC"1";
"B"
$PN"2"3;
"A"
$PN"1"19;
%"Q_RES"
"1","(4500,2125)","0","pure_quanta","I53";
;
PART_NUMBER"CS11302FB03"
PACK_TYPE"0402LF"
WATTAGE"1/16W"
MATERIAL"CHIP"
TOLERANCE"1%"
VALUE"130"
$LOCATION"R3091"
CDS_LIB"pure_quanta"
CDS_LOCATION"R3091"
$SEC"1"
CDS_SEC"1";
"B"
$PN"2"5;
"A"
$PN"1"27;
%"Q_RES"
"1","(4500,3375)","0","pure_quanta","I54";
;
PART_NUMBER"CS11302FB03"
PACK_TYPE"0402LF"
WATTAGE"1/16W"
MATERIAL"CHIP"
TOLERANCE"1%"
VALUE"130"
$LOCATION"R3090"
CDS_LIB"pure_quanta"
CDS_LOCATION"R3090"
$SEC"1"
CDS_SEC"1";
"B"
$PN"2"6;
"A"
$PN"1"28;
%"Q_RES"
"1","(4525,4700)","0","pure_quanta","I55";
;
PART_NUMBER"CS11302FB03"
PACK_TYPE"0402LF"
WATTAGE"1/16W"
MATERIAL"CHIP"
TOLERANCE"1%"
VALUE"130"
$LOCATION"R3092"
CDS_LIB"pure_quanta"
CDS_LOCATION"R3092"
$SEC"1"
CDS_SEC"1";
"B"
$PN"2"7;
"A"
$PN"1"29;
%"MOSFET_NCH_DUAL"
"2","(-2650,3100)","0","pure_quanta","I7";
;
PART_NUMBER"BAM138K0003"
PART_TYPE"SMLF"
VALUE"PJT138K"
MATERIAL"IC"
LOCATION"Q79"
CDS_LMAN_SYM_OUTLINE"-150,150,150,-150"
NEEDS_NO_SIZE"TRUE"
CDS_LIB"pure_quanta"
SEC_TYPE""
SEC"2";
"S2"
$PN"4"10;
"G2"
$PN"5"33;
"D2"
$PN"3"22;
%"MOSFET_NCH_DUAL"
"1","(-2650,4425)","0","pure_quanta","I8";
;
PART_NUMBER"BAM138K0003"
PART_TYPE"SMLF"
VALUE"PJT138K"
MATERIAL"IC"
LOCATION"Q79"
CDS_LIB"pure_quanta"
CDS_LMAN_SYM_OUTLINE"-150,150,150,-150"
NEEDS_NO_SIZE"TRUE"
$SEC"1"
CDS_SEC"1";
"D1"
$PN"6"31;
"G1"
$PN"2"32;
"S1"
$PN"1"11;
%"UNIVERSAL_GND"
"1","(-2600,200)","0","logical_power","I9";
;
CDS_LIB"logical_power"
HDL_POWER"GND";
"A"8;
END.
